#ISCELL
  pure_quanta quanta_title_block_c *
  *
#CELL
  pure_quanta pt5161lrs *
  page449_i1
#ISCELL
  standard tap *
  page449_i10
#ISCELL
  standard tap *
  page449_i11
#ISCELL
  standard tap *
  page449_i12
#ISCELL
  standard tap *
  page449_i13
#ISCELL
  standard tap *
  page449_i14
#ISCELL
  standard tap *
  page449_i15
#ISCELL
  standard tap *
  page449_i16
#ISCELL
  standard tap *
  page449_i17
#ISCELL
  standard offpage *
  page449_i18
#ISCELL
  standard offpage *
  page449_i19
#ISCELL
  standard tap *
  page449_i2
#ISCELL
  standard tap *
  page449_i20
#ISCELL
  standard tap *
  page449_i21
#ISCELL
  standard tap *
  page449_i22
#ISCELL
  standard tap *
  page449_i23
#ISCELL
  standard tap *
  page449_i24
#ISCELL
  standard tap *
  page449_i25
#ISCELL
  standard tap *
  page449_i26
#ISCELL
  standard tap *
  page449_i27
#ISCELL
  standard tap *
  page449_i28
#ISCELL
  standard tap *
  page449_i29
#ISCELL
  standard tap *
  page449_i3
#ISCELL
  standard tap *
  page449_i30
#ISCELL
  standard tap *
  page449_i31
#ISCELL
  standard tap *
  page449_i32
#ISCELL
  standard tap *
  page449_i33
#ISCELL
  standard tap *
  page449_i34
#ISCELL
  standard tap *
  page449_i35
#ISCELL
  standard offpage *
  page449_i36
#ISCELL
  standard offpage *
  page449_i37
#CELL
  pure_quanta pt5161lrs *
  page449_i38
#ISCELL
  standard tap *
  page449_i4
#ISCELL
  standard tap *
  page449_i5
#ISCELL
  standard tap *
  page449_i6
#ISCELL
  standard tap *
  page449_i7
#ISCELL
  standard tap *
  page449_i8
#ISCELL
  standard tap *
  page449_i9
